FILE_TYPE = CONNECTIVITY;
{Allegro Design Entry HDL 17.2-2016 S081 (4005846) 1/11/2022}
"PAGE_NUMBER" = 133;
0"NC";
1"P3V3_STBY\g";
2"P3V3_STBY\g";
3"GND\g";
4"P3V3_STBY\g";
5"P3V3_STBY\g";
6"P3V3_STBY\g";
7"P3V3_STBY\g";
8"P3V3_STBY\g";
9"FM_SYS_THROTTLE_BUF_R_N";
10"P3V3_STBY\g";
11"GND\g";
12"FM_SYS_THROTTLE_N"CDS_PHYS_NET_NAME"FM_SYS_THROTTLE_R_N";
13"FM_SYS_THROTTLE_BUF_N";
14"FM_SLOT3_PWRBRK_R1_N"CDS_PHYS_NET_NAME"FM_SYS_PWRBRK_LVC3_GENZ2_0_N";
15"FM_SLOT2_PWRBRK1_R1_N"CDS_PHYS_NET_NAME"FM_SYS_PWRBRK_LVC3_GENZ1_2_N";
16"FM_SLOT2_PWRBRK0_R1_N"CDS_PHYS_NET_NAME"FM_SYS_PWRBRK_LVC3_GENZ1_1_N";
17"FM_SLOT1_PWRBRK1_R1_N"CDS_PHYS_NET_NAME"FM_SYS_PWRBRK_LVC3_GENZ1_0_N";
18"FM_SLOT1_PWRBRK0_N";
19"FM_SLOT1_PWRBRK1_N";
20"FM_SLOT2_PWRBRK0_N";
21"FM_SLOT2_PWRBRK1_N";
22"FM_SLOT3_PWRBRK_N";
23"FM_SLOT1_PWRBRK0_R1_N"CDS_PHYS_NET_NAME"OCP2_PWRBRK_N";
24"OCP_PWRBRK_R1_N"CDS_PHYS_NET_NAME"OCP_PWRBRK_N";
25"OCP_PWRBRK_N";
%"UNIVERSAL_POWER"
"1","(-3925,5225)","0","pure_quanta_power","I18";
;
HDL_POWER"P3V3_STBY"
CDS_LIB"pure_quanta_power";
"A"1;
%"Q_RES"
"2","(-3925,5025)","0","pure_quanta","I19";
;
LOCATION"R984"
$SEC"1"
CDS_SEC"1"
WATTAGE"1/16W"
MATERIAL"CHIP"
TOLERANCE"1%"
VALUE"4.7K"
PART_NUMBER"CS24702FB10"
PACK_TYPE"0402LF"
CDS_LIB"pure_quanta";
"A"
$PN"1"1;
"B"
$PN"2"24;
%"UNIVERSAL_POWER"
"1","(-3925,4550)","0","pure_quanta_power","I22";
;
HDL_POWER"P3V3_STBY"
CDS_LIB"pure_quanta_power";
"A"2;
%"Q_RES"
"2","(-3925,4350)","0","pure_quanta","I23";
;
LOCATION"R985"
$SEC"1"
CDS_SEC"1"
WATTAGE"1/16W"
MATERIAL"CHIP"
TOLERANCE"1%"
VALUE"4.7K"
PART_NUMBER"CS24702FB10"
PACK_TYPE"0402LF"
CDS_LIB"pure_quanta";
"A"
$PN"1"2;
"B"
$PN"2"23;
%"Q_DIODE"
"1","(-4325,4650)","2","pure_quanta","I24";
;
LOCATION"D45"
$SEC"1"
CDS_SEC"1"
MATERIAL"IC"
VALUE"SDMK0340L-7-F"
PART_NUMBER"BC000340033"
PACK_TYPE"SMLF"
BOM_COST"MISC."
PIN_NAMES_ROTATE"True"
NEEDS_NO_SIZE"TRUE"
CDS_LIB"pure_quanta";
"1"
$PN"1"24;
"2"
$PN"2"9;
%"Q_DIODE"
"1","(-4300,3975)","2","pure_quanta","I26";
;
LOCATION"D53"
$SEC"1"
CDS_SEC"1"
MATERIAL"IC"
VALUE"SDMK0340L-7-F"
PART_NUMBER"BC000340033"
PACK_TYPE"SMLF"
CDS_LIB"pure_quanta"
BOM_COST"MISC."
PIN_NAMES_ROTATE"True"
NEEDS_NO_SIZE"TRUE";
"1"
$PN"1"23;
"2"
$PN"2"9;
%"Q_DIODE"
"1","(-4275,3300)","2","pure_quanta","I37";
;
LOCATION"D57"
$SEC"1"
CDS_SEC"1"
MATERIAL"IC"
VALUE"SDMK0340L-7-F"
PART_NUMBER"BC000340033"
PACK_TYPE"SMLF"
CDS_LIB"pure_quanta"
NEEDS_NO_SIZE"TRUE"
PIN_NAMES_ROTATE"True"
BOM_COST"MISC.";
"1"
$PN"1"17;
"2"
$PN"2"9;
%"Q_DIODE"
"1","(-4300,2575)","2","pure_quanta","I39";
;
LOCATION"D55"
$SEC"1"
CDS_SEC"1"
MATERIAL"IC"
VALUE"SDMK0340L-7-F"
PART_NUMBER"BC000340033"
PACK_TYPE"SMLF"
BOM_COST"MISC."
PIN_NAMES_ROTATE"True"
NEEDS_NO_SIZE"TRUE"
CDS_LIB"pure_quanta";
"1"
$PN"1"16;
"2"
$PN"2"9;
%"Q_DIODE"
"1","(-4325,1875)","2","pure_quanta","I40";
;
LOCATION"D47"
$SEC"1"
CDS_SEC"1"
MATERIAL"IC"
VALUE"SDMK0340L-7-F"
PART_NUMBER"BC000340033"
PACK_TYPE"SMLF"
BOM_COST"MISC."
PIN_NAMES_ROTATE"True"
NEEDS_NO_SIZE"TRUE"
CDS_LIB"pure_quanta";
"1"
$PN"1"15;
"2"
$PN"2"9;
%"Q_DIODE"
"1","(-4325,1150)","2","pure_quanta","I55";
;
LOCATION"D48"
$SEC"1"
CDS_SEC"1"
MATERIAL"IC"
VALUE"SDMK0340L-7-F"
PART_NUMBER"BC000340033"
PACK_TYPE"SMLF"
BOM_COST"MISC."
PIN_NAMES_ROTATE"True"
NEEDS_NO_SIZE"TRUE"
CDS_LIB"pure_quanta";
"1"
$PN"1"14;
"2"
$PN"2"9;
%"UNIVERSAL_GND"
"1","(-7325,4750)","2","pure_quanta_power","I67";
;
CDS_LIB"pure_quanta_power"
HDL_POWER"GND";
"A"3;
%"SN74LVC1G07DBVR"
"1","(-6975,4650)","0","pure_quanta","I68";
;
LOCATION"U81"
$SEC"1"
CDS_SEC"1"
PART_TYPE"SMLF"
MATERIAL"IC"
VALUE"SN74LVC1G07DBVR"
PART_NUMBER"AL1G0007024"
CDS_LIB"pure_quanta"
NEEDS_NO_SIZE"TRUE"
PACK_TYPE"SMLF";
"NC"
$PN"1"0;
"Y"
$PN"4"13;
"GND"
$PN"3"11;
"A"
$PN"2"12;
"VCC"
$PN"5"10;
%"Q_CAP"
"1","(-7325,4950)","2","pure_quanta","I69";
;
LOCATION"C550"
$SEC"1"
CDS_SEC"1"
MATERIAL"X7R"
TOLERANCE"10%"
VALUE"0.1UF"
PART_NUMBER"CH4104K1B00"
VOLTAGE"25V"
PACK_TYPE"0402"
CDS_LIB"pure_quanta";
"B"
$PN"2"3;
"A"
$PN"1"10;
%"UNIVERSAL_POWER"
"1","(-7250,5225)","0","pure_quanta_power","I70";
;
HDL_POWER"P3V3_STBY"
CDS_LIB"pure_quanta_power"
BOM_COST"OCP3.0 ";
"A"10;
%"Q_RES"
"1","(-5875,4650)","0","pure_quanta","I71";
;
LOCATION"R1324"
$SEC"1"
CDS_SEC"1"
VALUE"0"
BOM_COST"OCP3.0 "
CDS_LIB"pure_quanta"
WATTAGE"1/16W"
MATERIAL"CHIP"
TOLERANCE"5%"
PART_NUMBER"CS00002JB38"
PACK_TYPE"0402LF";
"B"
$PN"2"9;
"A"
$PN"1"13;
%"UNIVERSAL_GND"
"1","(-7225,4425)","2","pure_quanta_power","I73";
;
CDS_LIB"pure_quanta_power"
HDL_POWER"GND";
"A"11;
%"UNIVERSAL_POWER"
"1","(-4725,5225)","0","pure_quanta_power","I75";
;
HDL_POWER"P3V3_STBY"
CDS_LIB"pure_quanta_power";
"A"4;
%"Q_RES"
"2","(-4725,5025)","0","pure_quanta","I76";
;
LOCATION"R1325"
$SEC"1"
CDS_SEC"1"
WATTAGE"1/16W"
MATERIAL"CHIP"
TOLERANCE"1%"
VALUE"4.7K"
PART_NUMBER"CS24702FB10"
PACK_TYPE"0402LF"
CDS_LIB"pure_quanta";
"A"
$PN"1"4;
"B"
$PN"2"9;
%"Q_RES"
"2","(-3900,3675)","0","pure_quanta","I77";
;
LOCATION"R1326"
$SEC"1"
CDS_SEC"1"
WATTAGE"1/16W"
MATERIAL"CHIP"
TOLERANCE"1%"
VALUE"4.7K"
PART_NUMBER"CS24702FB10"
PACK_TYPE"0402LF"
CDS_LIB"pure_quanta";
"A"
$PN"1"5;
"B"
$PN"2"17;
%"UNIVERSAL_POWER"
"1","(-3900,3875)","0","pure_quanta_power","I78";
;
HDL_POWER"P3V3_STBY"
CDS_LIB"pure_quanta_power";
"A"5;
%"Q_RES"
"2","(-3875,2950)","0","pure_quanta","I79";
;
LOCATION"R1327"
$SEC"1"
CDS_SEC"1"
WATTAGE"1/16W"
MATERIAL"CHIP"
TOLERANCE"1%"
VALUE"4.7K"
PART_NUMBER"CS24702FB10"
PACK_TYPE"0402LF"
CDS_LIB"pure_quanta";
"A"
$PN"1"6;
"B"
$PN"2"16;
%"UNIVERSAL_POWER"
"1","(-3875,3150)","0","pure_quanta_power","I80";
;
HDL_POWER"P3V3_STBY"
CDS_LIB"pure_quanta_power";
"A"6;
%"Q_RES"
"2","(-3875,2250)","0","pure_quanta","I81";
;
LOCATION"R1328"
$SEC"1"
CDS_SEC"1"
WATTAGE"1/16W"
MATERIAL"CHIP"
TOLERANCE"1%"
VALUE"4.7K"
PART_NUMBER"CS24702FB10"
PACK_TYPE"0402LF"
CDS_LIB"pure_quanta";
"A"
$PN"1"7;
"B"
$PN"2"15;
%"UNIVERSAL_POWER"
"1","(-3875,2450)","0","pure_quanta_power","I82";
;
HDL_POWER"P3V3_STBY"
CDS_LIB"pure_quanta_power";
"A"7;
%"Q_RES"
"2","(-3875,1525)","0","pure_quanta","I83";
;
LOCATION"R1329"
$SEC"1"
CDS_SEC"1"
WATTAGE"1/16W"
MATERIAL"CHIP"
TOLERANCE"1%"
VALUE"4.7K"
PART_NUMBER"CS24702FB10"
PACK_TYPE"0402LF"
CDS_LIB"pure_quanta";
"A"
$PN"1"8;
"B"
$PN"2"14;
%"UNIVERSAL_POWER"
"1","(-3875,1725)","0","pure_quanta_power","I84";
;
HDL_POWER"P3V3_STBY"
CDS_LIB"pure_quanta_power";
"A"8;
%"Q_RES"
"1","(-2725,4650)","2","pure_quanta","I86";
;
LOCATION"R1222"
$SEC"1"
CDS_SEC"1"
VALUE"33"
BOM_COST"MEM"
CDS_LIB"pure_quanta"
WATTAGE"1/16W"
MATERIAL"CHIP"
TOLERANCE"5%"
PART_NUMBER"CS03302JB29"
PACK_TYPE"0402LF"
ROOM"RST_CPU0_PLD_TO_DIMM";
"B"
$PN"2"24;
"A"
$PN"1"25;
%"Q_RES"
"1","(-2725,3975)","2","pure_quanta","I92";
;
LOCATION"R1223"
$SEC"1"
CDS_SEC"1"
VALUE"33"
CDS_LIB"pure_quanta"
BOM_COST"MEM"
WATTAGE"1/16W"
MATERIAL"CHIP"
TOLERANCE"5%"
PART_NUMBER"CS03302JB29"
PACK_TYPE"0402LF"
ROOM"RST_CPU0_PLD_TO_DIMM";
"B"
$PN"2"23;
"A"
$PN"1"18;
%"Q_RES"
"1","(-2725,3300)","2","pure_quanta","I93";
;
LOCATION"R1224"
$SEC"1"
CDS_SEC"1"
VALUE"33"
CDS_LIB"pure_quanta"
BOM_COST"MEM"
WATTAGE"1/16W"
MATERIAL"CHIP"
TOLERANCE"5%"
PART_NUMBER"CS03302JB29"
PACK_TYPE"0402LF"
ROOM"RST_CPU0_PLD_TO_DIMM";
"B"
$PN"2"17;
"A"
$PN"1"19;
%"Q_RES"
"1","(-2725,2575)","2","pure_quanta","I94";
;
LOCATION"R1231"
$SEC"1"
CDS_SEC"1"
VALUE"33"
BOM_COST"MEM"
CDS_LIB"pure_quanta"
WATTAGE"1/16W"
MATERIAL"CHIP"
TOLERANCE"5%"
PART_NUMBER"CS03302JB29"
PACK_TYPE"0402LF"
ROOM"RST_CPU0_PLD_TO_DIMM";
"B"
$PN"2"16;
"A"
$PN"1"20;
%"Q_RES"
"1","(-2725,1875)","2","pure_quanta","I95";
;
LOCATION"R1243"
$SEC"1"
CDS_SEC"1"
VALUE"33"
BOM_COST"MEM"
CDS_LIB"pure_quanta"
WATTAGE"1/16W"
MATERIAL"CHIP"
TOLERANCE"5%"
PART_NUMBER"CS03302JB29"
PACK_TYPE"0402LF"
ROOM"RST_CPU0_PLD_TO_DIMM";
"B"
$PN"2"15;
"A"
$PN"1"21;
%"Q_RES"
"1","(-2725,1150)","2","pure_quanta","I96";
;
LOCATION"R1244"
$SEC"1"
CDS_SEC"1"
VALUE"33"
BOM_COST"MEM"
CDS_LIB"pure_quanta"
WATTAGE"1/16W"
MATERIAL"CHIP"
TOLERANCE"5%"
PART_NUMBER"CS03302JB29"
PACK_TYPE"0402LF"
ROOM"RST_CPU0_PLD_TO_DIMM";
"B"
$PN"2"14;
"A"
$PN"1"22;
END.
